(kicad_pcb
	(version 20260206)
	(generator "pcbnew")
	(generator_version "10.0")
	(general
		(thickness 1.6)
		(legacy_teardrops no)
	)
	(paper "A4")
	(title_block
		(title "Bryce Canyon_F.DPB_16315-1-OCP.brd")
		(comment 1 "Bryce Canyon / footprints 2116-2123 of 2223")
	)
	(layers
		(0 "F.Cu" signal "TOP")
		(4 "In1.Cu" signal "L2GND")
		(6 "In2.Cu" signal "L3")
		(8 "In3.Cu" signal "L4GND")
		(10 "In4.Cu" signal "L5")
		(12 "In5.Cu" signal "L6VCC")
		(14 "In6.Cu" signal "L7VCC")
		(16 "In7.Cu" signal "L8")
		(18 "In8.Cu" signal "L9GND")
		(20 "In9.Cu" signal "L10")
		(22 "In10.Cu" signal "L11GND")
		(2 "B.Cu" signal "BOTTOM")
		(9 "F.Adhes" user "F.Adhesive")
		(11 "B.Adhes" user "B.Adhesive")
		(13 "F.Paste" user "Package Geometry/Pastemask Top")
		(15 "B.Paste" user "Package Geometry/Pastemask Bottom")
		(5 "F.SilkS" user "Ref Des/Silkscreen Top")
		(7 "B.SilkS" user "Ref Des/Silkscreen Bottom")
		(1 "F.Mask" user "Board Geometry/Soldermask Top")
		(3 "B.Mask" user "Board Geometry/Soldermask Bottom")
		(17 "Dwgs.User" user "User.Drawings")
		(19 "Cmts.User" user "User.Comments")
		(21 "Eco1.User" user "User.Eco1")
		(23 "Eco2.User" user "User.Eco2")
		(25 "Edge.Cuts" user "Board Geometry/Outline")
		(27 "Margin" user)
		(31 "F.CrtYd" user "Package Geometry/Place Bound Top")
		(29 "B.CrtYd" user "Package Geometry/Place Bound Bottom")
		(35 "F.Fab" user "Ref Des/Assembly Top")
		(33 "B.Fab" user "Ref Des/Assembly Bottom")
	)
	(footprint ""
		(layer "B.Cu")
		(at 481.823522 -228.4095 180)
		(property "Reference" "R1262"
			(at 0 0 0)
			(layer "B.SilkS")
			(hide yes)
			(effects
				(font
					(size 1.27 1.27)
				)
				(justify mirror)
			)
		)
		(property "Value" "49K9R2F-L-GP"
			(at -0.064008 -3.993896 180)
			(unlocked yes)
			(layer "B.Fab")
			(hide yes)
			(effects
				(font
					(size 1.016 1.016)
					(thickness 0.1524)
				)
				(justify mirror)
			)
		)
		(property "Device Type" "R402H16"
			(at -0.064008 -5.517896 180)
			(unlocked yes)
			(layer "B.Fab")
			(hide yes)
			(effects
				(font
					(size 1.016 1.016)
					(thickness 0.1524)
				)
				(justify mirror)
			)
		)
		(duplicate_pad_numbers_are_jumpers no)
		(fp_line
			(start 0.508 -0.9398)
			(end 0.508 0.9398)
			(stroke
				(width 0.1524)
				(type default)
			)
			(layer "B.SilkS")
		)
		(fp_line
			(start -0.508 -0.9398)
			(end 0.508 -0.9398)
			(stroke
				(width 0.1524)
				(type default)
			)
			(layer "B.SilkS")
		)
		(fp_rect
			(start 0.508 0.9398)
			(end -0.508 -0.9398)
			(stroke
				(width 0)
				(type default)
			)
			(fill no)
			(layer "B.CrtYd")
		)
		(fp_rect
			(start 0.508 0.9398)
			(end -0.508 -0.9398)
			(stroke
				(width 0)
				(type default)
			)
			(fill no)
			(layer "B.Fab")
		)
		(pad "1" smd custom
			(at 0 -0.4445)
			(size 0.1397 0.1397)
			(layers "B.Cu" "B.Mask" "B.Paste")
			(net "P12V_A")
			(options
				(clearance outline)
				(anchor circle)
			)
			(primitives
				(gr_poly
					(pts
						(arc
							(start -0.1778 0.2794)
							(mid -0.249642 0.249642)
							(end -0.2794 0.1778)
						)
						(arc
							(start -0.2794 -0.1778)
							(mid -0.249642 -0.249642)
							(end -0.1778 -0.2794)
						)
						(arc
							(start 0.1778 -0.2794)
							(mid 0.249642 -0.249642)
							(end 0.2794 -0.1778)
						)
						(arc
							(start 0.2794 0.1778)
							(mid 0.249642 0.249642)
							(end 0.1778 0.2794)
						)
					)
					(width 0)
					(fill yes)
				)
			)
		)
		(pad "2" smd custom
			(at 0 0.4445)
			(size 0.1397 0.1397)
			(layers "B.Cu" "B.Mask" "B.Paste")
			(net "P5V_D_EN_R")
			(options
				(clearance outline)
				(anchor circle)
			)
			(primitives
				(gr_poly
					(pts
						(arc
							(start -0.1778 0.2794)
							(mid -0.249642 0.249642)
							(end -0.2794 0.1778)
						)
						(arc
							(start -0.2794 -0.1778)
							(mid -0.249642 -0.249642)
							(end -0.1778 -0.2794)
						)
						(arc
							(start 0.1778 -0.2794)
							(mid 0.249642 -0.249642)
							(end 0.2794 -0.1778)
						)
						(arc
							(start 0.2794 0.1778)
							(mid 0.249642 0.249642)
							(end 0.1778 0.2794)
						)
					)
					(width 0)
					(fill yes)
				)
			)
		)
	)
	(footprint ""
		(layer "B.Cu")
		(at 189.073282 -234.871006 180)
		(property "Reference" "G2"
			(at 0 0 0)
			(layer "B.SilkS")
			(hide yes)
			(effects
				(font
					(size 1.27 1.27)
				)
				(justify mirror)
			)
		)
		(property "Value" "GAP-CLOSE-PWR-4-GP"
			(at 2.4638 -0.5461 180)
			(unlocked yes)
			(layer "B.Fab")
			(hide yes)
			(effects
				(font
					(size 1.016 1.016)
					(thickness 0.1524)
				)
				(justify mirror)
			)
		)
		(property "Device Type" "GAP-CLOSE-PWR-4"
			(at 2.4638 -2.0701 180)
			(unlocked yes)
			(layer "B.Fab")
			(hide yes)
			(effects
				(font
					(size 1.016 1.016)
					(thickness 0.1524)
				)
				(justify mirror)
			)
		)
		(duplicate_pad_numbers_are_jumpers no)
		(fp_rect
			(start 0.2794 0.254)
			(end -0.2794 -0.254)
			(stroke
				(width 0)
				(type default)
			)
			(fill no)
			(layer "B.CrtYd")
		)
		(fp_rect
			(start 0.2794 0.254)
			(end -0.2794 -0.254)
			(stroke
				(width 0)
				(type default)
			)
			(fill no)
			(layer "B.Fab")
		)
		(pad "1" smd rect
			(at 0.0635 0)
			(size 0.1778 0.254)
			(layers "B.Cu" "B.Mask" "B.Paste")
			(net "P3V3_STBY_A")
		)
		(pad "2" smd rect
			(at -0.0635 0)
			(size 0.1778 0.254)
			(layers "B.Cu" "B.Mask" "B.Paste")
			(net "P3V3_STBY_CC")
		)
	)
	(footprint ""
		(layer "B.Cu")
		(at 465.598764 -230.606346 90)
		(property "Reference" "R1266"
			(at 0 0 90)
			(layer "B.SilkS")
			(hide yes)
			(effects
				(font
					(size 1.27 1.27)
				)
				(justify mirror)
			)
		)
		(property "Value" "0R3J-0-U-GP"
			(at 0.0254 -2.5146 90)
			(unlocked yes)
			(layer "B.Fab")
			(hide yes)
			(effects
				(font
					(size 1.016 1.016)
					(thickness 0.1524)
				)
				(justify mirror)
			)
		)
		(property "Device Type" "R603H22"
			(at 0.0254 -4.0386 90)
			(unlocked yes)
			(layer "B.Fab")
			(hide yes)
			(effects
				(font
					(size 1.016 1.016)
					(thickness 0.1524)
				)
				(justify mirror)
			)
		)
		(duplicate_pad_numbers_are_jumpers no)
		(fp_line
			(start 0.4826 0)
			(end 0.2032 0)
			(stroke
				(width 0.2032)
				(type default)
			)
			(layer "B.SilkS")
		)
		(fp_line
			(start -0.2032 0)
			(end -0.4826 0)
			(stroke
				(width 0.2032)
				(type default)
			)
			(layer "B.SilkS")
		)
		(fp_rect
			(start 0.5842 1.3335)
			(end -0.5842 -1.3335)
			(stroke
				(width 0)
				(type default)
			)
			(fill no)
			(layer "B.CrtYd")
		)
		(fp_rect
			(start 0.5842 1.3335)
			(end -0.5842 -1.3335)
			(stroke
				(width 0)
				(type default)
			)
			(fill no)
			(layer "B.Fab")
		)
		(pad "1" smd custom
			(at 0 -0.762 270)
			(size 0.2159 0.2159)
			(layers "B.Cu" "B.Mask" "B.Paste")
			(net "P5V_D_VBST")
			(options
				(clearance outline)
				(anchor circle)
			)
			(primitives
				(gr_poly
					(pts
						(arc
							(start -0.3302 0.4318)
							(mid -0.402042 0.402042)
							(end -0.4318 0.3302)
						)
						(arc
							(start -0.4318 -0.3302)
							(mid -0.402042 -0.402042)
							(end -0.3302 -0.4318)
						)
						(arc
							(start 0.3302 -0.4318)
							(mid 0.402042 -0.402042)
							(end 0.4318 -0.3302)
						)
						(arc
							(start 0.4318 0.3302)
							(mid 0.402042 0.402042)
							(end 0.3302 0.4318)
						)
					)
					(width 0)
					(fill yes)
				)
			)
		)
		(pad "2" smd custom
			(at 0 0.762 270)
			(size 0.2159 0.2159)
			(layers "B.Cu" "B.Mask" "B.Paste")
			(net "P5V_D_VBST_RC")
			(options
				(clearance outline)
				(anchor circle)
			)
			(primitives
				(gr_poly
					(pts
						(arc
							(start -0.3302 0.4318)
							(mid -0.402042 0.402042)
							(end -0.4318 0.3302)
						)
						(arc
							(start -0.4318 -0.3302)
							(mid -0.402042 -0.402042)
							(end -0.3302 -0.4318)
						)
						(arc
							(start 0.3302 -0.4318)
							(mid 0.402042 -0.402042)
							(end 0.4318 -0.3302)
						)
						(arc
							(start 0.4318 0.3302)
							(mid 0.402042 0.402042)
							(end 0.3302 0.4318)
						)
					)
					(width 0)
					(fill yes)
				)
			)
		)
	)
	(footprint ""
		(layer "B.Cu")
		(at 181.801516 -222.747332 -90)
		(property "Reference" "R1291"
			(at 0 0 90)
			(layer "B.SilkS")
			(hide yes)
			(effects
				(font
					(size 1.27 1.27)
				)
				(justify mirror)
			)
		)
		(property "Value" "15KR2F-GP"
			(at -0.064008 -3.993896 270)
			(unlocked yes)
			(layer "B.Fab")
			(hide yes)
			(effects
				(font
					(size 1.016 1.016)
					(thickness 0.1524)
				)
				(justify mirror)
			)
		)
		(property "Device Type" "R402H16"
			(at -0.064008 -5.517896 270)
			(unlocked yes)
			(layer "B.Fab")
			(hide yes)
			(effects
				(font
					(size 1.016 1.016)
					(thickness 0.1524)
				)
				(justify mirror)
			)
		)
		(duplicate_pad_numbers_are_jumpers no)
		(fp_line
			(start -0.508 -0.9398)
			(end 0.508 -0.9398)
			(stroke
				(width 0.1524)
				(type default)
			)
			(layer "B.SilkS")
		)
		(fp_line
			(start 0.508 -0.9398)
			(end 0.508 0.9398)
			(stroke
				(width 0.1524)
				(type default)
			)
			(layer "B.SilkS")
		)
		(fp_rect
			(start 0.508 0.9398)
			(end -0.508 -0.9398)
			(stroke
				(width 0)
				(type default)
			)
			(fill no)
			(layer "B.CrtYd")
		)
		(fp_rect
			(start 0.508 0.9398)
			(end -0.508 -0.9398)
			(stroke
				(width 0)
				(type default)
			)
			(fill no)
			(layer "B.Fab")
		)
		(pad "1" smd custom
			(at 0 -0.4445 90)
			(size 0.1397 0.1397)
			(layers "B.Cu" "B.Mask" "B.Paste")
			(net "PWRGD_P3V3_STBY")
			(options
				(clearance outline)
				(anchor circle)
			)
			(primitives
				(gr_poly
					(pts
						(arc
							(start -0.1778 0.2794)
							(mid -0.249642 0.249642)
							(end -0.2794 0.1778)
						)
						(arc
							(start -0.2794 -0.1778)
							(mid -0.249642 -0.249642)
							(end -0.1778 -0.2794)
						)
						(arc
							(start 0.1778 -0.2794)
							(mid 0.249642 -0.249642)
							(end 0.2794 -0.1778)
						)
						(arc
							(start 0.2794 0.1778)
							(mid 0.249642 0.249642)
							(end 0.1778 0.2794)
						)
					)
					(width 0)
					(fill yes)
				)
			)
		)
		(pad "2" smd custom
			(at 0 0.4445 90)
			(size 0.1397 0.1397)
			(layers "B.Cu" "B.Mask" "B.Paste")
			(net "GND")
			(options
				(clearance outline)
				(anchor circle)
			)
			(primitives
				(gr_poly
					(pts
						(arc
							(start -0.1778 0.2794)
							(mid -0.249642 0.249642)
							(end -0.2794 0.1778)
						)
						(arc
							(start -0.2794 -0.1778)
							(mid -0.249642 -0.249642)
							(end -0.1778 -0.2794)
						)
						(arc
							(start 0.1778 -0.2794)
							(mid 0.249642 -0.249642)
							(end 0.2794 -0.1778)
						)
						(arc
							(start 0.2794 0.1778)
							(mid 0.249642 0.249642)
							(end 0.1778 0.2794)
						)
					)
					(width 0)
					(fill yes)
				)
			)
		)
	)
	(footprint ""
		(layer "B.Cu")
		(at 190.934594 -223.448118)
		(property "Reference" "C669"
			(at 0 0 0)
			(layer "B.SilkS")
			(hide yes)
			(effects
				(font
					(size 1.27 1.27)
				)
				(justify mirror)
			)
		)
		(property "Value" "SC1U16V3KX-5GP"
			(at 0 -2.8194 0)
			(unlocked yes)
			(layer "B.Fab")
			(hide yes)
			(effects
				(font
					(size 1.016 1.016)
					(thickness 0.1524)
				)
				(justify mirror)
			)
		)
		(property "Device Type" "C603H36"
			(at 0 -4.3434 0)
			(unlocked yes)
			(layer "B.Fab")
			(hide yes)
			(effects
				(font
					(size 1.016 1.016)
					(thickness 0.1524)
				)
				(justify mirror)
			)
		)
		(duplicate_pad_numbers_are_jumpers no)
		(fp_line
			(start -0.508 0)
			(end 0.508 0)
			(stroke
				(width 0.2032)
				(type default)
			)
			(layer "B.SilkS")
		)
		(fp_rect
			(start 0.5842 1.3335)
			(end -0.5842 -1.3335)
			(stroke
				(width 0)
				(type default)
			)
			(fill no)
			(layer "B.CrtYd")
		)
		(fp_rect
			(start 0.5842 1.3335)
			(end -0.5842 -1.3335)
			(stroke
				(width 0)
				(type default)
			)
			(fill no)
			(layer "B.Fab")
		)
		(pad "1" smd custom
			(at 0 -0.762 180)
			(size 0.2159 0.2159)
			(layers "B.Cu" "B.Mask" "B.Paste")
			(net "P3V3_STBY_VCC")
			(options
				(clearance outline)
				(anchor circle)
			)
			(primitives
				(gr_poly
					(pts
						(arc
							(start -0.3302 0.4318)
							(mid -0.402042 0.402042)
							(end -0.4318 0.3302)
						)
						(arc
							(start -0.4318 -0.3302)
							(mid -0.402042 -0.402042)
							(end -0.3302 -0.4318)
						)
						(arc
							(start 0.3302 -0.4318)
							(mid 0.402042 -0.402042)
							(end 0.4318 -0.3302)
						)
						(arc
							(start 0.4318 0.3302)
							(mid 0.402042 0.402042)
							(end 0.3302 0.4318)
						)
					)
					(width 0)
					(fill yes)
				)
			)
		)
		(pad "2" smd custom
			(at 0 0.762 180)
			(size 0.2159 0.2159)
			(layers "B.Cu" "B.Mask" "B.Paste")
			(net "GND")
			(options
				(clearance outline)
				(anchor circle)
			)
			(primitives
				(gr_poly
					(pts
						(arc
							(start -0.3302 0.4318)
							(mid -0.402042 0.402042)
							(end -0.4318 0.3302)
						)
						(arc
							(start -0.4318 -0.3302)
							(mid -0.402042 -0.402042)
							(end -0.3302 -0.4318)
						)
						(arc
							(start 0.3302 -0.4318)
							(mid 0.402042 -0.402042)
							(end 0.4318 -0.3302)
						)
						(arc
							(start 0.4318 0.3302)
							(mid 0.402042 0.402042)
							(end 0.3302 0.4318)
						)
					)
					(width 0)
					(fill yes)
				)
			)
		)
	)
	(footprint ""
		(layer "B.Cu")
		(at 49.215802 -149.79015 90)
		(property "Reference" "C666"
			(at 0 0 90)
			(layer "B.SilkS")
			(hide yes)
			(effects
				(font
					(size 1.27 1.27)
				)
				(justify mirror)
			)
		)
		(property "Value" "SC68P50V2JN-2-GP"
			(at -1.1811 -2.7051 90)
			(unlocked yes)
			(layer "B.Fab")
			(hide yes)
			(effects
				(font
					(size 1.016 1.016)
					(thickness 0.1524)
				)
				(justify mirror)
			)
		)
		(property "Device Type" "C402H22"
			(at -1.1811 -4.2291 90)
			(unlocked yes)
			(layer "B.Fab")
			(hide yes)
			(effects
				(font
					(size 1.016 1.016)
					(thickness 0.1524)
				)
				(justify mirror)
			)
		)
		(duplicate_pad_numbers_are_jumpers no)
		(fp_rect
			(start 0.4318 0.9525)
			(end -0.4318 -0.9525)
			(stroke
				(width 0)
				(type default)
			)
			(fill no)
			(layer "B.CrtYd")
		)
		(fp_rect
			(start 0.4318 0.9525)
			(end -0.4318 -0.9525)
			(stroke
				(width 0)
				(type default)
			)
			(fill no)
			(layer "B.Fab")
		)
		(pad "1" smd custom
			(at 0 -0.4445 270)
			(size 0.1524 0.1524)
			(layers "B.Cu" "B.Mask" "B.Paste")
			(net "P5V_B_VFB")
			(options
				(clearance outline)
				(anchor circle)
			)
			(primitives
				(gr_poly
					(pts
						(arc
							(start 0.3048 0.2032)
							(mid 0.275042 0.275042)
							(end 0.2032 0.3048)
						)
						(arc
							(start -0.2032 0.3048)
							(mid -0.275042 0.275042)
							(end -0.3048 0.2032)
						)
						(arc
							(start -0.3048 -0.2032)
							(mid -0.275042 -0.275042)
							(end -0.2032 -0.3048)
						)
						(arc
							(start 0.2032 -0.3048)
							(mid 0.275042 -0.275042)
							(end 0.3048 -0.2032)
						)
					)
					(width 0)
					(fill yes)
				)
			)
		)
		(pad "2" smd custom
			(at 0 0.4445 270)
			(size 0.1524 0.1524)
			(layers "B.Cu" "B.Mask" "B.Paste")
			(net "P5V_B_VFB_R")
			(options
				(clearance outline)
				(anchor circle)
			)
			(primitives
				(gr_poly
					(pts
						(arc
							(start 0.3048 0.2032)
							(mid 0.275042 0.275042)
							(end 0.2032 0.3048)
						)
						(arc
							(start -0.2032 0.3048)
							(mid -0.275042 0.275042)
							(end -0.3048 0.2032)
						)
						(arc
							(start -0.3048 -0.2032)
							(mid -0.275042 -0.275042)
							(end -0.2032 -0.3048)
						)
						(arc
							(start 0.2032 -0.3048)
							(mid 0.275042 -0.275042)
							(end 0.3048 -0.2032)
						)
					)
					(width 0)
					(fill yes)
				)
			)
		)
	)
	(footprint ""
		(layer "B.Cu")
		(at 33.909 -139.2936 90)
		(property "Reference" "L3"
			(at 0 0 90)
			(layer "B.SilkS")
			(hide yes)
			(effects
				(font
					(size 1.27 1.27)
				)
				(justify mirror)
			)
		)
		(property "Value" "BLM21PG220SN1DGP"
			(at -0.0254 -5.6896 90)
			(unlocked yes)
			(layer "B.Fab")
			(hide yes)
			(effects
				(font
					(size 1.016 1.016)
					(thickness 0.1524)
				)
				(justify mirror)
			)
		)
		(property "Device Type" "L20125H42"
			(at -0.0254 -7.5946 90)
			(unlocked yes)
			(layer "B.Fab")
			(hide yes)
			(effects
				(font
					(size 1.016 1.016)
					(thickness 0.1524)
				)
				(justify mirror)
			)
		)
		(duplicate_pad_numbers_are_jumpers no)
		(fp_line
			(start 0.9144 -1.7018)
			(end 0.9144 1.7018)
			(stroke
				(width 0.1524)
				(type default)
			)
			(layer "B.SilkS")
		)
		(fp_line
			(start -0.9144 -1.7018)
			(end 0.9144 -1.7018)
			(stroke
				(width 0.1524)
				(type default)
			)
			(layer "B.SilkS")
		)
		(fp_line
			(start 0.9144 1.7018)
			(end -0.9144 1.7018)
			(stroke
				(width 0.1524)
				(type default)
			)
			(layer "B.SilkS")
		)
		(fp_line
			(start -0.9144 1.7018)
			(end -0.9144 -1.7018)
			(stroke
				(width 0.1524)
				(type default)
			)
			(layer "B.SilkS")
		)
		(fp_rect
			(start 1.0033 1.778)
			(end -1.0033 -1.778)
			(stroke
				(width 0)
				(type default)
			)
			(fill no)
			(layer "B.CrtYd")
		)
		(fp_poly
			(pts
				(xy 1.0033 -1.778) (xy -1.0033 -1.778) (xy -1.0033 1.778) (xy 1.0033 1.778)
			)
			(stroke
				(width 0)
				(type default)
			)
			(fill no)
			(layer "B.Fab")
		)
		(pad "1" smd rect
			(at 0 -0.9652 270)
			(size 1.397 1.143)
			(layers "B.Cu" "B.Mask" "B.Paste")
			(net "P12V_A")
		)
		(pad "2" smd rect
			(at 0 0.9652 270)
			(size 1.397 1.143)
			(layers "B.Cu" "B.Mask" "B.Paste")
			(net "P12V_A_VIN_U21")
		)
	)
	(footprint ""
		(layer "B.Cu")
		(at 480.536758 -223.215962 180)
		(property "Reference" "C660"
			(at 0 0 0)
			(layer "B.SilkS")
			(hide yes)
			(effects
				(font
					(size 1.27 1.27)
				)
				(justify mirror)
			)
		)
		(property "Value" "SC470P50V2KX-3GP"
			(at -1.1811 -2.7051 180)
			(unlocked yes)
			(layer "B.Fab")
			(hide yes)
			(effects
				(font
					(size 1.016 1.016)
					(thickness 0.1524)
				)
				(justify mirror)
			)
		)
		(property "Device Type" "C402H22"
			(at -1.1811 -4.2291 180)
			(unlocked yes)
			(layer "B.Fab")
			(hide yes)
			(effects
				(font
					(size 1.016 1.016)
					(thickness 0.1524)
				)
				(justify mirror)
			)
		)
		(duplicate_pad_numbers_are_jumpers no)
		(fp_rect
			(start 0.4318 0.9525)
			(end -0.4318 -0.9525)
			(stroke
				(width 0)
				(type default)
			)
			(fill no)
			(layer "B.CrtYd")
		)
		(fp_rect
			(start 0.4318 0.9525)
			(end -0.4318 -0.9525)
			(stroke
				(width 0)
				(type default)
			)
			(fill no)
			(layer "B.Fab")
		)
		(pad "1" smd custom
			(at 0 -0.4445)
			(size 0.1524 0.1524)
			(layers "B.Cu" "B.Mask" "B.Paste")
			(net "P5V_D_LL_R")
			(options
				(clearance outline)
				(anchor circle)
			)
			(primitives
				(gr_poly
					(pts
						(arc
							(start 0.3048 0.2032)
							(mid 0.275042 0.275042)
							(end 0.2032 0.3048)
						)
						(arc
							(start -0.2032 0.3048)
							(mid -0.275042 0.275042)
							(end -0.3048 0.2032)
						)
						(arc
							(start -0.3048 -0.2032)
							(mid -0.275042 -0.275042)
							(end -0.2032 -0.3048)
						)
						(arc
							(start 0.2032 -0.3048)
							(mid 0.275042 -0.275042)
							(end 0.3048 -0.2032)
						)
					)
					(width 0)
					(fill yes)
				)
			)
		)
		(pad "2" smd custom
			(at 0 0.4445)
			(size 0.1524 0.1524)
			(layers "B.Cu" "B.Mask" "B.Paste")
			(net "P5V_D_VFB")
			(options
				(clearance outline)
				(anchor circle)
			)
			(primitives
				(gr_poly
					(pts
						(arc
							(start 0.3048 0.2032)
							(mid 0.275042 0.275042)
							(end 0.2032 0.3048)
						)
						(arc
							(start -0.2032 0.3048)
							(mid -0.275042 0.275042)
							(end -0.3048 0.2032)
						)
						(arc
							(start -0.3048 -0.2032)
							(mid -0.275042 -0.275042)
							(end -0.2032 -0.3048)
						)
						(arc
							(start 0.2032 -0.3048)
							(mid 0.275042 -0.275042)
							(end 0.3048 -0.2032)
						)
					)
					(width 0)
					(fill yes)
				)
			)
		)
	)
)
